# T6G (Grand Teton) — schematic netlist excerpt (pin names and nets, part order shuffled) for the footprints in the layout excerpt that follows; sources: Cadence DE-HDL packaged netlist, KiCad conversion of 04192023_DAF0TMB3IC0_F0TG_MB_C_brd_V02_OCP.brd

C6538  Q_CAP_DIFFBUS  DIFF BUS_0.22UF 6.3V 20% X6S  pkg C0201  page 286 : \1\ = P5E_CPU0_P1_TX_BUF_C_DN<2> ; \2\ = P5E_CPU0_P1_TX_BUF_DN<2>
R4119  Q_RES  54.9K 1% EMPTY  pkg 0402LF  page 125 : A = P3V3_AUX ; B = GPU_3V3IO_RSVD0_FFU
R6805  Q_RES  0 5% CHIP  pkg 0402LF  page 81 : A = RST_RT_CPU0_P0_RESET_R_N ; B = RST_RT_CPU0_P0_RESET_R2_N

(kicad_pcb
	(version 20260206)
	(generator "pcbnew")
	(generator_version "10.0")
	(general
		(thickness 1.6)
		(legacy_teardrops no)
	)
	(paper "A4")
	(title_block
		(title "04192023_DAF0TMB3IC0_F0TG_MB_C_brd_V02_OCP.brd")
		(comment 1 "Grand Teton / footprints 5517-5519 of 8354")
	)
	(layers
		(0 "F.Cu" signal "TOP")
		(4 "In1.Cu" signal "GND")
		(6 "In2.Cu" signal "IN1")
		(8 "In3.Cu" signal "GND1")
		(10 "In4.Cu" signal "IN2")
		(12 "In5.Cu" signal "GND2")
		(14 "In6.Cu" signal "IN3")
		(16 "In7.Cu" signal "GND3")
		(18 "In8.Cu" signal "VCC")
		(20 "In9.Cu" signal "VCC1")
		(22 "In10.Cu" signal "GND4")
		(24 "In11.Cu" signal "IN4")
		(26 "In12.Cu" signal "GND5")
		(28 "In13.Cu" signal "IN5")
		(30 "In14.Cu" signal "GND6")
		(32 "In15.Cu" signal "IN6")
		(34 "In16.Cu" signal "GND7")
		(2 "B.Cu" signal "BOTTOM")
		(9 "F.Adhes" user "F.Adhesive")
		(11 "B.Adhes" user "B.Adhesive")
		(13 "F.Paste" user "Package Geometry/Pastemask Top")
		(15 "B.Paste" user "Package Geometry/Pastemask Bottom")
		(5 "F.SilkS" user "Ref Des/Silkscreen Top")
		(7 "B.SilkS" user "Ref Des/Silkscreen Bottom")
		(1 "F.Mask" user "Board Geometry/Soldermask Top")
		(3 "B.Mask" user "Board Geometry/Soldermask Bottom")
		(17 "Dwgs.User" user "User.Drawings")
		(19 "Cmts.User" user "User.Comments")
		(21 "Eco1.User" user "User.Eco1")
		(23 "Eco2.User" user "User.Eco2")
		(25 "Edge.Cuts" user "Board Geometry/Outline")
		(27 "Margin" user)
		(31 "F.CrtYd" user "Package Geometry/Place Bound Top")
		(29 "B.CrtYd" user "Package Geometry/Place Bound Bottom")
		(35 "F.Fab" user "Ref Des/Assembly Top")
		(33 "B.Fab" user "Ref Des/Assembly Bottom")
	)
	(footprint ""
		(layer "B.Cu")
		(at 184.257696 -133.791452 90)
		(property "Reference" "R6805"
			(at 0 0 90)
			(layer "B.SilkS")
			(hide yes)
			(effects
				(font
					(size 1.27 1.27)
				)
				(justify mirror)
			)
		)
		(property "Value" ""
			(at 0 0 90)
			(layer "B.Fab")
			(effects
				(font
					(size 1.27 1.27)
				)
				(justify mirror)
			)
		)
		(duplicate_pad_numbers_are_jumpers no)
		(fp_line
			(start 0.7874 -0.4064)
			(end -0.7874 -0.4064)
			(stroke
				(width 0.1524)
				(type default)
			)
			(layer "B.SilkS")
		)
		(fp_line
			(start -0.7874 -0.4064)
			(end -0.7874 0.4064)
			(stroke
				(width 0.1524)
				(type default)
			)
			(layer "B.SilkS")
		)
		(fp_line
			(start 0.7874 0.4064)
			(end 0.7874 -0.4064)
			(stroke
				(width 0.1524)
				(type default)
			)
			(layer "B.SilkS")
		)
		(fp_line
			(start -0.7874 0.4064)
			(end 0.7874 0.4064)
			(stroke
				(width 0.1524)
				(type default)
			)
			(layer "B.SilkS")
		)
		(fp_line
			(start 0.67945 -0.305054)
			(end 0.12065 -0.305054)
			(stroke
				(width 0.1)
				(type default)
			)
			(layer "B.Fab")
		)
		(fp_line
			(start 0.12065 -0.305054)
			(end 0.12065 -0.2794)
			(stroke
				(width 0.1)
				(type default)
			)
			(layer "B.Fab")
		)
		(fp_line
			(start -0.12065 -0.3048)
			(end -0.67945 -0.3048)
			(stroke
				(width 0.1)
				(type default)
			)
			(layer "B.Fab")
		)
		(fp_line
			(start -0.67945 -0.3048)
			(end -0.67945 0.3048)
			(stroke
				(width 0.1)
				(type default)
			)
			(layer "B.Fab")
		)
		(fp_line
			(start 0.12065 -0.2794)
			(end -0.12065 -0.2794)
			(stroke
				(width 0.1)
				(type default)
			)
			(layer "B.Fab")
		)
		(fp_line
			(start -0.12065 -0.2794)
			(end -0.12065 -0.3048)
			(stroke
				(width 0.1)
				(type default)
			)
			(layer "B.Fab")
		)
		(fp_line
			(start 0.12065 0.2794)
			(end 0.12065 0.3048)
			(stroke
				(width 0.1)
				(type default)
			)
			(layer "B.Fab")
		)
		(fp_line
			(start -0.120396 0.2794)
			(end 0.12065 0.2794)
			(stroke
				(width 0.1)
				(type default)
			)
			(layer "B.Fab")
		)
		(fp_line
			(start 0.67945 0.3048)
			(end 0.67945 -0.305054)
			(stroke
				(width 0.1)
				(type default)
			)
			(layer "B.Fab")
		)
		(fp_line
			(start 0.12065 0.3048)
			(end 0.67945 0.3048)
			(stroke
				(width 0.1)
				(type default)
			)
			(layer "B.Fab")
		)
		(fp_line
			(start -0.120396 0.3048)
			(end -0.120396 0.2794)
			(stroke
				(width 0.1)
				(type default)
			)
			(layer "B.Fab")
		)
		(fp_line
			(start -0.67945 0.3048)
			(end -0.120396 0.3048)
			(stroke
				(width 0.1)
				(type default)
			)
			(layer "B.Fab")
		)
		(pad "1" smd circle
			(at 0.40005 0 270)
			(size 0 0)
			(layers "B.Cu" "B.Mask" "B.Paste")
			(net "RST_RT_CPU0_P0_RESET_R_N")
		)
		(pad "2" smd circle
			(at -0.40005 0 270)
			(size 0 0)
			(layers "B.Cu" "B.Mask" "B.Paste")
			(net "RST_RT_CPU0_P0_RESET_R2_N")
		)
	)
	(footprint ""
		(layer "B.Cu")
		(at 311.426606 -416.899344 90)
		(property "Reference" "C6538"
			(at 0 0 90)
			(layer "B.SilkS")
			(hide yes)
			(effects
				(font
					(size 1.27 1.27)
				)
				(justify mirror)
			)
		)
		(property "Value" ""
			(at 0 0 90)
			(layer "B.Fab")
			(effects
				(font
					(size 1.27 1.27)
				)
				(justify mirror)
			)
		)
		(duplicate_pad_numbers_are_jumpers no)
		(fp_line
			(start 0.299974 -0.150114)
			(end -0.299974 -0.150114)
			(stroke
				(width 0.1)
				(type default)
			)
			(layer "B.Fab")
		)
		(fp_line
			(start -0.299974 -0.150114)
			(end -0.299974 0.150114)
			(stroke
				(width 0.1)
				(type default)
			)
			(layer "B.Fab")
		)
		(fp_line
			(start 0.299974 0.150114)
			(end 0.299974 -0.150114)
			(stroke
				(width 0.1)
				(type default)
			)
			(layer "B.Fab")
		)
		(fp_line
			(start -0.299974 0.150114)
			(end 0.299974 0.150114)
			(stroke
				(width 0.1)
				(type default)
			)
			(layer "B.Fab")
		)
		(pad "1" smd rect
			(at 0.2667 0 270)
			(size 0.3048 0.381)
			(layers "B.Cu" "B.Mask" "B.Paste")
			(net "P5E_CPU0_P1_TX_BUF_C_DN<2>")
		)
		(pad "2" smd rect
			(at -0.2667 0 270)
			(size 0.3048 0.381)
			(layers "B.Cu" "B.Mask" "B.Paste")
			(net "P5E_CPU0_P1_TX_BUF_DN<2>")
		)
	)
	(footprint ""
		(layer "B.Cu")
		(at 165.599618 -416.946588 180)
		(property "Reference" "R4119"
			(at 0 0 0)
			(layer "B.SilkS")
			(hide yes)
			(effects
				(font
					(size 1.27 1.27)
				)
				(justify mirror)
			)
		)
		(property "Value" ""
			(at 0 0 0)
			(layer "B.Fab")
			(effects
				(font
					(size 1.27 1.27)
				)
				(justify mirror)
			)
		)
		(duplicate_pad_numbers_are_jumpers no)
		(fp_line
			(start 0.7874 0.4064)
			(end 0.7874 -0.4064)
			(stroke
				(width 0.1524)
				(type default)
			)
			(layer "B.SilkS")
		)
		(fp_line
			(start 0.7874 -0.4064)
			(end -0.7874 -0.4064)
			(stroke
				(width 0.1524)
				(type default)
			)
			(layer "B.SilkS")
		)
		(fp_line
			(start -0.7874 0.4064)
			(end 0.7874 0.4064)
			(stroke
				(width 0.1524)
				(type default)
			)
			(layer "B.SilkS")
		)
		(fp_line
			(start -0.7874 -0.4064)
			(end -0.7874 0.4064)
			(stroke
				(width 0.1524)
				(type default)
			)
			(layer "B.SilkS")
		)
		(fp_line
			(start 0.67945 0.3048)
			(end 0.67945 -0.305054)
			(stroke
				(width 0.1)
				(type default)
			)
			(layer "B.Fab")
		)
		(fp_line
			(start 0.67945 -0.305054)
			(end 0.12065 -0.305054)
			(stroke
				(width 0.1)
				(type default)
			)
			(layer "B.Fab")
		)
		(fp_line
			(start 0.12065 0.3048)
			(end 0.67945 0.3048)
			(stroke
				(width 0.1)
				(type default)
			)
			(layer "B.Fab")
		)
		(fp_line
			(start 0.12065 0.2794)
			(end 0.12065 0.3048)
			(stroke
				(width 0.1)
				(type default)
			)
			(layer "B.Fab")
		)
		(fp_line
			(start 0.12065 -0.2794)
			(end -0.12065 -0.2794)
			(stroke
				(width 0.1)
				(type default)
			)
			(layer "B.Fab")
		)
		(fp_line
			(start 0.12065 -0.305054)
			(end 0.12065 -0.2794)
			(stroke
				(width 0.1)
				(type default)
			)
			(layer "B.Fab")
		)
		(fp_line
			(start -0.120396 0.3048)
			(end -0.120396 0.2794)
			(stroke
				(width 0.1)
				(type default)
			)
			(layer "B.Fab")
		)
		(fp_line
			(start -0.120396 0.2794)
			(end 0.12065 0.2794)
			(stroke
				(width 0.1)
				(type default)
			)
			(layer "B.Fab")
		)
		(fp_line
			(start -0.12065 -0.2794)
			(end -0.12065 -0.3048)
			(stroke
				(width 0.1)
				(type default)
			)
			(layer "B.Fab")
		)
		(fp_line
			(start -0.12065 -0.3048)
			(end -0.67945 -0.3048)
			(stroke
				(width 0.1)
				(type default)
			)
			(layer "B.Fab")
		)
		(fp_line
			(start -0.67945 0.3048)
			(end -0.120396 0.3048)
			(stroke
				(width 0.1)
				(type default)
			)
			(layer "B.Fab")
		)
		(fp_line
			(start -0.67945 -0.3048)
			(end -0.67945 0.3048)
			(stroke
				(width 0.1)
				(type default)
			)
			(layer "B.Fab")
		)
		(pad "1" smd circle
			(at 0.40005 0)
			(size 0 0)
			(layers "B.Cu" "B.Mask" "B.Paste")
			(net "P3V3_AUX")
		)
		(pad "2" smd circle
			(at -0.40005 0)
			(size 0 0)
			(layers "B.Cu" "B.Mask" "B.Paste")
			(net "GPU_3V3IO_RSVD0_FFU")
		)
	)
)
